# S9S_MB_2U (Grand Teton) — schematic netlist excerpt (pin names and nets, part order shuffled) for the footprints in the layout excerpt that follows; sources: Cadence DE-HDL packaged netlist, KiCad conversion of 03242023_DA0F0TMBIJ0_F0T_Motherboard_J_brd_V01_OCP.brd

C712  Q_CAP_DIFFBUS  DIFF BUS_0.22UF 6.3V 20% X6S  pkg C0201  page 176 : \1\ = P5E_CPU1_PE0_TX_C_DN<14> ; \2\ = P5E_CPU1_PE0_TX_DN<14>
PC1249  Q_CAP  1UF 16V 10% X6S  pkg C0402  page 281 : A = SW_P12V_PVCCIN_CPU0_FLT ; B = GND

PD17  SS15P3SM386A  SS15P3S-M3/86A IC  pkg TO277A_4-3X6-1  page 304
  ANODE_1  = GND
  ANODE_2  = GND
  CATHODE  = P12V_AUX

(kicad_pcb
	(version 20260206)
	(generator "pcbnew")
	(generator_version "10.0")
	(general
		(thickness 1.6)
		(legacy_teardrops no)
	)
	(paper "A4")
	(title_block
		(title "03242023_DA0F0TMBIJ0_F0T_Motherboard_J_brd_V01_OCP.brd")
		(comment 1 "Grand Teton / footprints 3266-3268 of 6105")
	)
	(layers
		(0 "F.Cu" signal "TOP")
		(4 "In1.Cu" signal "GND")
		(6 "In2.Cu" signal "IN1")
		(8 "In3.Cu" signal "GND1")
		(10 "In4.Cu" signal "IN2")
		(12 "In5.Cu" signal "GND2")
		(14 "In6.Cu" signal "IN3")
		(16 "In7.Cu" signal "GND3")
		(18 "In8.Cu" signal "VCC")
		(20 "In9.Cu" signal "VCC1")
		(22 "In10.Cu" signal "GND4")
		(24 "In11.Cu" signal "IN4")
		(26 "In12.Cu" signal "GND5")
		(28 "In13.Cu" signal "IN5")
		(30 "In14.Cu" signal "GND6")
		(32 "In15.Cu" signal "IN6")
		(34 "In16.Cu" signal "GND7")
		(2 "B.Cu" signal "BOTTOM")
		(9 "F.Adhes" user "F.Adhesive")
		(11 "B.Adhes" user "B.Adhesive")
		(13 "F.Paste" user "Package Geometry/Pastemask Top")
		(15 "B.Paste" user "Package Geometry/Pastemask Bottom")
		(5 "F.SilkS" user "Ref Des/Silkscreen Top")
		(7 "B.SilkS" user "Ref Des/Silkscreen Bottom")
		(1 "F.Mask" user "Board Geometry/Soldermask Top")
		(3 "B.Mask" user "Board Geometry/Soldermask Bottom")
		(17 "Dwgs.User" user "User.Drawings")
		(19 "Cmts.User" user "User.Comments")
		(21 "Eco1.User" user "User.Eco1")
		(23 "Eco2.User" user "User.Eco2")
		(25 "Edge.Cuts" user "Board Geometry/Outline")
		(27 "Margin" user)
		(31 "F.CrtYd" user "Package Geometry/Place Bound Top")
		(29 "B.CrtYd" user "Package Geometry/Place Bound Bottom")
		(35 "F.Fab" user "Ref Des/Assembly Top")
		(33 "B.Fab" user "Ref Des/Assembly Bottom")
	)
	(footprint ""
		(layer "F.Cu")
		(at 236.015784 -391.837164 90)
		(property "Reference" "PD17"
			(at -2.8956 -3.343148 90)
			(unlocked yes)
			(layer "F.SilkS")
			(effects
				(font
					(size 0.7874 0.5842)
					(thickness 0.1524)
				)
			)
		)
		(property "Value" ""
			(at 0 0 90)
			(layer "F.Fab")
			(effects
				(font
					(size 1.27 1.27)
				)
			)
		)
		(duplicate_pad_numbers_are_jumpers no)
		(fp_line
			(start 3.541776 -2.54)
			(end 3.541776 2.54)
			(stroke
				(width 0.1524)
				(type default)
			)
			(layer "F.SilkS")
		)
		(fp_line
			(start -3.539744 -2.54)
			(end 3.541776 -2.54)
			(stroke
				(width 0.1524)
				(type default)
			)
			(layer "F.SilkS")
		)
		(fp_line
			(start 3.541776 2.54)
			(end -3.539744 2.54)
			(stroke
				(width 0.1524)
				(type default)
			)
			(layer "F.SilkS")
		)
		(fp_line
			(start -3.539744 2.54)
			(end -3.539744 -2.54)
			(stroke
				(width 0.1524)
				(type default)
			)
			(layer "F.SilkS")
		)
		(fp_poly
			(pts
				(xy -4.699 0.531876) (xy -4.699 1.547876) (xy -3.683 1.039876)
			)
			(stroke
				(width 0)
				(type default)
			)
			(fill yes)
			(layer "F.SilkS")
		)
		(fp_line
			(start 3.074924 -2.175002)
			(end 3.074924 2.175002)
			(stroke
				(width 0.1)
				(type default)
			)
			(layer "F.Fab")
		)
		(fp_line
			(start -3.074924 -2.175002)
			(end 3.074924 -2.175002)
			(stroke
				(width 0.1)
				(type default)
			)
			(layer "F.Fab")
		)
		(fp_line
			(start 3.074924 2.175002)
			(end -3.074924 2.175002)
			(stroke
				(width 0.1)
				(type default)
			)
			(layer "F.Fab")
		)
		(fp_line
			(start -3.074924 2.175002)
			(end -3.074924 -2.175002)
			(stroke
				(width 0.1)
				(type default)
			)
			(layer "F.Fab")
		)
		(fp_poly
			(pts
				(xy -4.699 0.531876) (xy -4.699 1.547876) (xy -3.683 1.039876)
			)
			(stroke
				(width 0)
				(type default)
			)
			(fill yes)
			(layer "F.Fab")
		)
		(pad "1" smd rect
			(at -2.765044 1.039876 270)
			(size 1.27 1.4224)
			(layers "F.Cu" "F.Mask" "F.Paste")
			(net "GND")
		)
		(pad "2" smd rect
			(at -2.765044 -1.039876 270)
			(size 1.27 1.4224)
			(layers "F.Cu" "F.Mask" "F.Paste")
			(net "GND")
		)
		(pad "K" smd rect
			(at 1.039876 0 270)
			(size 4.7244 4.8006)
			(layers "F.Cu" "F.Mask" "F.Paste")
			(net "P12V_AUX")
		)
	)
	(footprint ""
		(layer "F.Cu")
		(at 51.017678 -402.371052 -90)
		(property "Reference" "C712"
			(at 0 0 270)
			(layer "F.SilkS")
			(hide yes)
			(effects
				(font
					(size 1.27 1.27)
				)
			)
		)
		(property "Value" ""
			(at 0 0 270)
			(layer "F.Fab")
			(effects
				(font
					(size 1.27 1.27)
				)
			)
		)
		(duplicate_pad_numbers_are_jumpers no)
		(fp_line
			(start -0.299974 0.150114)
			(end -0.299974 -0.150114)
			(stroke
				(width 0.1)
				(type default)
			)
			(layer "F.Fab")
		)
		(fp_line
			(start 0.299974 0.150114)
			(end -0.299974 0.150114)
			(stroke
				(width 0.1)
				(type default)
			)
			(layer "F.Fab")
		)
		(fp_line
			(start -0.299974 -0.150114)
			(end 0.299974 -0.150114)
			(stroke
				(width 0.1)
				(type default)
			)
			(layer "F.Fab")
		)
		(fp_line
			(start 0.299974 -0.150114)
			(end 0.299974 0.150114)
			(stroke
				(width 0.1)
				(type default)
			)
			(layer "F.Fab")
		)
		(pad "1" smd rect
			(at -0.2667 0 270)
			(size 0.3048 0.381)
			(layers "F.Cu" "F.Mask" "F.Paste")
			(net "P5E_CPU1_PE0_TX_C_DN<14>")
		)
		(pad "2" smd rect
			(at 0.2667 0 270)
			(size 0.3048 0.381)
			(layers "F.Cu" "F.Mask" "F.Paste")
			(net "P5E_CPU1_PE0_TX_DN<14>")
		)
	)
	(footprint ""
		(layer "F.Cu")
		(at 372.871238 -361.704382 180)
		(property "Reference" "PC1249"
			(at 0 0 180)
			(layer "F.SilkS")
			(hide yes)
			(effects
				(font
					(size 1.27 1.27)
				)
			)
		)
		(property "Value" ""
			(at 0 0 180)
			(layer "F.Fab")
			(effects
				(font
					(size 1.27 1.27)
				)
			)
		)
		(duplicate_pad_numbers_are_jumpers no)
		(fp_line
			(start 0.7874 0.4064)
			(end -0.7874 0.4064)
			(stroke
				(width 0.1524)
				(type default)
			)
			(layer "F.SilkS")
		)
		(fp_line
			(start 0.7874 -0.4064)
			(end 0.7874 0.4064)
			(stroke
				(width 0.1524)
				(type default)
			)
			(layer "F.SilkS")
		)
		(fp_line
			(start -0.7874 0.4064)
			(end -0.7874 -0.4064)
			(stroke
				(width 0.1524)
				(type default)
			)
			(layer "F.SilkS")
		)
		(fp_line
			(start -0.7874 -0.4064)
			(end 0.7874 -0.4064)
			(stroke
				(width 0.1524)
				(type default)
			)
			(layer "F.SilkS")
		)
		(fp_line
			(start 0.67945 0.3048)
			(end 0.120396 0.3048)
			(stroke
				(width 0.1)
				(type default)
			)
			(layer "F.Fab")
		)
		(fp_line
			(start 0.67945 -0.3048)
			(end 0.67945 0.3048)
			(stroke
				(width 0.1)
				(type default)
			)
			(layer "F.Fab")
		)
		(fp_line
			(start 0.12065 -0.2794)
			(end 0.12065 -0.3048)
			(stroke
				(width 0.1)
				(type default)
			)
			(layer "F.Fab")
		)
		(fp_line
			(start 0.12065 -0.3048)
			(end 0.67945 -0.3048)
			(stroke
				(width 0.1)
				(type default)
			)
			(layer "F.Fab")
		)
		(fp_line
			(start 0.120396 0.3048)
			(end 0.120396 0.2794)
			(stroke
				(width 0.1)
				(type default)
			)
			(layer "F.Fab")
		)
		(fp_line
			(start 0.120396 0.2794)
			(end -0.12065 0.2794)
			(stroke
				(width 0.1)
				(type default)
			)
			(layer "F.Fab")
		)
		(fp_line
			(start -0.12065 0.3048)
			(end -0.67945 0.3048)
			(stroke
				(width 0.1)
				(type default)
			)
			(layer "F.Fab")
		)
		(fp_line
			(start -0.12065 0.2794)
			(end -0.12065 0.3048)
			(stroke
				(width 0.1)
				(type default)
			)
			(layer "F.Fab")
		)
		(fp_line
			(start -0.12065 -0.2794)
			(end 0.12065 -0.2794)
			(stroke
				(width 0.1)
				(type default)
			)
			(layer "F.Fab")
		)
		(fp_line
			(start -0.12065 -0.305054)
			(end -0.12065 -0.2794)
			(stroke
				(width 0.1)
				(type default)
			)
			(layer "F.Fab")
		)
		(fp_line
			(start -0.67945 0.3048)
			(end -0.67945 -0.305054)
			(stroke
				(width 0.1)
				(type default)
			)
			(layer "F.Fab")
		)
		(fp_line
			(start -0.67945 -0.305054)
			(end -0.12065 -0.305054)
			(stroke
				(width 0.1)
				(type default)
			)
			(layer "F.Fab")
		)
		(pad "1" smd circle
			(at -0.40005 0 180)
			(size 0 0)
			(layers "F.Cu" "F.Mask" "F.Paste")
			(net "SW_P12V_PVCCIN_CPU0_FLT")
		)
		(pad "2" smd circle
			(at 0.40005 0 180)
			(size 0 0)
			(layers "F.Cu" "F.Mask" "F.Paste")
			(net "GND")
		)
	)
)
